(kicad_pcb
	(version 20241229)
	(generator "pcbnew")
	(generator_version "9.0")
	(general
		(thickness 1.61)
		(legacy_teardrops no)
	)
	(paper "A3")
	(title_block
		(title "SO-DIMM DDR5 Tester")
		(date "2025-11-26")
		(rev "1.3.0")
		(comment 9 "footprints 554-559 of 627")
	)
	(layers
		(0 "F.Cu" signal)
		(4 "In1.Cu" power)
		(6 "In2.Cu" mixed)
		(8 "In3.Cu" power)
		(10 "In4.Cu" mixed)
		(12 "In5.Cu" power)
		(14 "In6.Cu" mixed)
		(16 "In7.Cu" power)
		(18 "In8.Cu" power)
		(20 "In9.Cu" mixed)
		(22 "In10.Cu" power)
		(2 "B.Cu" signal)
		(9 "F.Adhes" user "F.Adhesive")
		(11 "B.Adhes" user "B.Adhesive")
		(13 "F.Paste" user)
		(15 "B.Paste" user)
		(5 "F.SilkS" user "F.Silkscreen")
		(7 "B.SilkS" user "B.Silkscreen")
		(1 "F.Mask" user)
		(3 "B.Mask" user)
		(17 "Dwgs.User" user "User.Drawings")
		(19 "Cmts.User" user "User.Comments")
		(21 "Eco1.User" user "User.Eco1")
		(23 "Eco2.User" user "User.Eco2")
		(25 "Edge.Cuts" user)
		(27 "Margin" user)
		(31 "F.CrtYd" user "F.Courtyard")
		(29 "B.CrtYd" user "B.Courtyard")
		(35 "F.Fab" user)
		(33 "B.Fab" user)
	)
	(footprint "antmicro-footprints:TP_SMD_1mm"
		(layer "B.Cu")
		(at 186.4 184.85 180)
		(property "Reference" "TP28"
			(at 0 0.731898 0)
			(layer "B.SilkS")
			(hide yes)
			(effects
				(font
					(size 0.7 0.7)
					(thickness 0.15)
				)
				(justify left bottom mirror)
			)
		)
		(property "Value" "TP_1mm_SMD"
			(at 0 -1.4 0)
			(layer "B.Fab")
			(effects
				(font
					(size 0.7 0.7)
					(thickness 0.15)
				)
				(justify left bottom mirror)
			)
		)
		(property "MPN" ""
			(at 0 0 0)
			(unlocked yes)
			(layer "B.Fab")
			(hide yes)
			(effects
				(font
					(size 1 1)
					(thickness 0.15)
				)
				(justify mirror)
			)
		)
		(property "Manufacturer" ""
			(at 0 0 0)
			(unlocked yes)
			(layer "B.Fab")
			(hide yes)
			(effects
				(font
					(size 1 1)
					(thickness 0.15)
				)
				(justify mirror)
			)
		)
		(property "Author" "Antmicro"
			(at 0 0 0)
			(unlocked yes)
			(layer "B.Fab")
			(hide yes)
			(effects
				(font
					(size 1 1)
					(thickness 0.15)
				)
				(justify mirror)
			)
		)
		(property "License" "Apache-2.0"
			(at 0 0 0)
			(unlocked yes)
			(layer "B.Fab")
			(hide yes)
			(effects
				(font
					(size 1 1)
					(thickness 0.15)
				)
				(justify mirror)
			)
		)
		(sheetname "/Supply/")
		(sheetfile "supply.kicad_sch")
		(attr exclude_from_pos_files)
		(fp_circle
			(center 0 0)
			(end 0.6 0)
			(stroke
				(width 0.05)
				(type default)
			)
			(fill no)
			(layer "B.CrtYd")
		)
		(fp_text user "Author: Antmicro"
			(at -0.5 -4 0)
			(layer "B.Fab")
			(effects
				(font
					(size 0.7 0.7)
					(thickness 0.15)
				)
				(justify left bottom mirror)
			)
		)
		(fp_text user "${REFERENCE}"
			(at -0.5 -2.8 0)
			(layer "B.Fab")
			(effects
				(font
					(size 0.7 0.7)
					(thickness 0.15)
				)
				(justify left bottom mirror)
			)
		)
		(fp_text user "License: Apache-2.0"
			(at -0.5 -5.2 0)
			(layer "B.Fab")
			(effects
				(font
					(size 0.7 0.7)
					(thickness 0.15)
				)
				(justify left bottom mirror)
			)
		)
		(pad "1" smd circle
			(at 0 0 180)
			(size 1 1)
			(layers "B.Cu" "B.Mask")
			(net 187 "+1V0_MGTAVCC")
			(pinfunction "1")
			(pintype "passive")
		)
	)
	(footprint "antmicro-footprints:C_0603_1608Metric"
		(layer "B.Cu")
		(at 147.375501 174.801 180)
		(descr "Capacitor SMD 0603")
		(tags "capacitor 0603")
		(property "Reference" "C73"
			(at 0 0.9 0)
			(layer "B.SilkS")
			(hide yes)
			(effects
				(font
					(size 0.7 0.7)
					(thickness 0.15)
				)
				(justify left bottom mirror)
			)
		)
		(property "Value" "C_47u_0603"
			(at 0 -1.6 0)
			(layer "B.Fab")
			(effects
				(font
					(size 0.7 0.7)
					(thickness 0.15)
				)
				(justify left bottom mirror)
			)
		)
		(property "Datasheet" "https://www.murata.com/products/productdetail?partno=GRM188R60J476ME15%23"
			(at 0 0 180)
			(layer "F.Fab")
			(hide yes)
			(effects
				(font
					(size 1.27 1.27)
					(thickness 0.15)
				)
			)
		)
		(property "Author" "Antmicro"
			(at 294.751002 349.602 0)
			(layer "B.Fab")
			(hide yes)
			(effects
				(font
					(size 1 1)
					(thickness 0.15)
				)
				(justify mirror)
			)
		)
		(property "Dielectric" ""
			(at 294.751002 349.602 0)
			(layer "B.Fab")
			(hide yes)
			(effects
				(font
					(size 1 1)
					(thickness 0.15)
				)
				(justify mirror)
			)
		)
		(property "License" "Apache-2.0"
			(at 294.751002 349.602 0)
			(layer "B.Fab")
			(hide yes)
			(effects
				(font
					(size 1 1)
					(thickness 0.15)
				)
				(justify mirror)
			)
		)
		(property "MPN" "GRM188R60J476ME15D"
			(at 294.751002 349.602 0)
			(layer "B.Fab")
			(hide yes)
			(effects
				(font
					(size 1 1)
					(thickness 0.15)
				)
				(justify mirror)
			)
		)
		(property "Manufacturer" "Murata"
			(at 294.751002 349.602 0)
			(layer "B.Fab")
			(hide yes)
			(effects
				(font
					(size 1 1)
					(thickness 0.15)
				)
				(justify mirror)
			)
		)
		(property "Val" "47u"
			(at 294.751002 349.602 0)
			(layer "B.Fab")
			(hide yes)
			(effects
				(font
					(size 1 1)
					(thickness 0.15)
				)
				(justify mirror)
			)
		)
		(property "Voltage" ""
			(at 294.751002 349.602 0)
			(layer "B.Fab")
			(hide yes)
			(effects
				(font
					(size 1 1)
					(thickness 0.15)
				)
				(justify mirror)
			)
		)
		(sheetname "/FPGA power/")
		(sheetfile "fpga-power.kicad_sch")
		(attr smd)
		(fp_line
			(start -0.3 0.3)
			(end 0.3 0.3)
			(stroke
				(width 0.15)
				(type solid)
			)
			(layer "B.SilkS")
		)
		(fp_line
			(start -0.3 -0.3)
			(end 0.3 -0.3)
			(stroke
				(width 0.15)
				(type solid)
			)
			(layer "B.SilkS")
		)
		(fp_rect
			(start -1.24 0.7)
			(end 1.24 -0.7)
			(stroke
				(width 0.05)
				(type solid)
			)
			(fill no)
			(layer "B.CrtYd")
		)
		(fp_rect
			(start -0.8 0.4)
			(end 0.8 -0.4)
			(stroke
				(width 0.15)
				(type solid)
			)
			(fill no)
			(layer "B.Fab")
		)
		(pad "1" smd roundrect
			(at -0.7 0 180)
			(size 0.6 0.8)
			(layers "B.Cu" "B.Mask" "B.Paste")
			(roundrect_rratio 0.2)
			(net 200 "+3V3")
			(pintype "passive")
		)
		(pad "2" smd roundrect
			(at 0.7 0 180)
			(size 0.6 0.8)
			(layers "B.Cu" "B.Mask" "B.Paste")
			(roundrect_rratio 0.2)
			(net 1 "GND")
			(pintype "passive")
		)
	)
	(footprint "antmicro-footprints:C_0402_1005Metric"
		(layer "B.Cu")
		(at 133.375501 166.801 90)
		(descr "Capacitor SMD 0402 (1005 Metric), square (rectangular) end terminal, IPC_7351 nominal, (Body size source: IPC-SM-782 page 76, https://www.pcb-3d.com/wordpress/wp-content/uploads/ipc-sm-782a_amendment_1_and_2.pdf)")
		(tags "capacitor 0402")
		(property "Reference" "C31"
			(at 0 1.17 270)
			(layer "B.SilkS")
			(hide yes)
			(effects
				(font
					(size 0.7 0.7)
					(thickness 0.15)
				)
				(justify left bottom mirror)
			)
		)
		(property "Value" "C_100n_0402"
			(at 0 -1.169 270)
			(layer "B.Fab")
			(effects
				(font
					(size 0.7 0.7)
					(thickness 0.15)
				)
				(justify left bottom mirror)
			)
		)
		(property "Datasheet" "https://www.murata.com/products/productdetail?partno=GRM155R61H104KE14%23"
			(at 0 0 90)
			(layer "F.Fab")
			(hide yes)
			(effects
				(font
					(size 1.27 1.27)
					(thickness 0.15)
				)
			)
		)
		(property "Author" "Antmicro"
			(at 300.176501 33.425499 0)
			(layer "B.Fab")
			(hide yes)
			(effects
				(font
					(size 1 1)
					(thickness 0.15)
				)
				(justify mirror)
			)
		)
		(property "Dielectric" "X5R"
			(at 300.176501 33.425499 0)
			(layer "B.Fab")
			(hide yes)
			(effects
				(font
					(size 1 1)
					(thickness 0.15)
				)
				(justify mirror)
			)
		)
		(property "License" "Apache-2.0"
			(at 300.176501 33.425499 0)
			(layer "B.Fab")
			(hide yes)
			(effects
				(font
					(size 1 1)
					(thickness 0.15)
				)
				(justify mirror)
			)
		)
		(property "MPN" "GRM155R61H104KE14D"
			(at 300.176501 33.425499 0)
			(layer "B.Fab")
			(hide yes)
			(effects
				(font
					(size 1 1)
					(thickness 0.15)
				)
				(justify mirror)
			)
		)
		(property "Manufacturer" "Murata"
			(at 300.176501 33.425499 0)
			(layer "B.Fab")
			(hide yes)
			(effects
				(font
					(size 1 1)
					(thickness 0.15)
				)
				(justify mirror)
			)
		)
		(property "Val" "100n"
			(at 300.176501 33.425499 0)
			(layer "B.Fab")
			(hide yes)
			(effects
				(font
					(size 1 1)
					(thickness 0.15)
				)
				(justify mirror)
			)
		)
		(property "Voltage" "50V"
			(at 300.176501 33.425499 0)
			(layer "B.Fab")
			(hide yes)
			(effects
				(font
					(size 1 1)
					(thickness 0.15)
				)
				(justify mirror)
			)
		)
		(sheetname "/FPGA power/")
		(sheetfile "fpga-power.kicad_sch")
		(attr smd)
		(fp_rect
			(start -0.9656 0.4572)
			(end 0.9652 -0.4828)
			(stroke
				(width 0.05)
				(type solid)
			)
			(fill no)
			(layer "B.CrtYd")
		)
		(fp_line
			(start 0.498 -0.248)
			(end -0.5 -0.248)
			(stroke
				(width 0.15)
				(type solid)
			)
			(layer "B.Fab")
		)
		(fp_line
			(start -0.5 -0.248)
			(end -0.5 0.25)
			(stroke
				(width 0.15)
				(type solid)
			)
			(layer "B.Fab")
		)
		(fp_line
			(start 0.498 0.25)
			(end 0.498 -0.248)
			(stroke
				(width 0.15)
				(type solid)
			)
			(layer "B.Fab")
		)
		(fp_line
			(start -0.5 0.25)
			(end 0.498 0.25)
			(stroke
				(width 0.15)
				(type solid)
			)
			(layer "B.Fab")
		)
		(pad "1" smd roundrect
			(at -0.5 0)
			(size 0.6 0.6)
			(layers "B.Cu" "B.Mask" "B.Paste")
			(roundrect_rratio 0.25)
			(net 1 "GND")
			(pintype "passive")
		)
		(pad "2" smd roundrect
			(at 0.498 0 90)
			(size 0.6 0.6)
			(layers "B.Cu" "B.Mask" "B.Paste")
			(roundrect_rratio 0.25)
			(net 206 "+1V1")
			(pintype "passive")
		)
	)
	(footprint "antmicro-footprints:C_0402_1005Metric"
		(layer "B.Cu")
		(at 151.375501 162.801 -90)
		(descr "Capacitor SMD 0402 (1005 Metric), square (rectangular) end terminal, IPC_7351 nominal, (Body size source: IPC-SM-782 page 76, https://www.pcb-3d.com/wordpress/wp-content/uploads/ipc-sm-782a_amendment_1_and_2.pdf)")
		(tags "capacitor 0402")
		(property "Reference" "C89"
			(at 0 1.17 90)
			(layer "B.SilkS")
			(hide yes)
			(effects
				(font
					(size 0.7 0.7)
					(thickness 0.15)
				)
				(justify left bottom mirror)
			)
		)
		(property "Value" "C_100n_0402"
			(at 0 -1.169 90)
			(layer "B.Fab")
			(effects
				(font
					(size 0.7 0.7)
					(thickness 0.15)
				)
				(justify left bottom mirror)
			)
		)
		(property "Datasheet" "https://www.murata.com/products/productdetail?partno=GRM155R61H104KE14%23"
			(at 0 0 270)
			(layer "F.Fab")
			(hide yes)
			(effects
				(font
					(size 1.27 1.27)
					(thickness 0.15)
				)
			)
		)
		(property "Author" "Antmicro"
			(at -11.425499 314.176501 0)
			(layer "B.Fab")
			(hide yes)
			(effects
				(font
					(size 1 1)
					(thickness 0.15)
				)
				(justify mirror)
			)
		)
		(property "Dielectric" "X5R"
			(at -11.425499 314.176501 0)
			(layer "B.Fab")
			(hide yes)
			(effects
				(font
					(size 1 1)
					(thickness 0.15)
				)
				(justify mirror)
			)
		)
		(property "License" "Apache-2.0"
			(at -11.425499 314.176501 0)
			(layer "B.Fab")
			(hide yes)
			(effects
				(font
					(size 1 1)
					(thickness 0.15)
				)
				(justify mirror)
			)
		)
		(property "MPN" "GRM155R61H104KE14D"
			(at -11.425499 314.176501 0)
			(layer "B.Fab")
			(hide yes)
			(effects
				(font
					(size 1 1)
					(thickness 0.15)
				)
				(justify mirror)
			)
		)
		(property "Manufacturer" "Murata"
			(at -11.425499 314.176501 0)
			(layer "B.Fab")
			(hide yes)
			(effects
				(font
					(size 1 1)
					(thickness 0.15)
				)
				(justify mirror)
			)
		)
		(property "Val" "100n"
			(at -11.425499 314.176501 0)
			(layer "B.Fab")
			(hide yes)
			(effects
				(font
					(size 1 1)
					(thickness 0.15)
				)
				(justify mirror)
			)
		)
		(property "Voltage" "50V"
			(at -11.425499 314.176501 0)
			(layer "B.Fab")
			(hide yes)
			(effects
				(font
					(size 1 1)
					(thickness 0.15)
				)
				(justify mirror)
			)
		)
		(sheetname "/FPGA power/")
		(sheetfile "fpga-power.kicad_sch")
		(attr smd)
		(fp_rect
			(start -0.9656 0.4572)
			(end 0.9652 -0.4828)
			(stroke
				(width 0.05)
				(type solid)
			)
			(fill no)
			(layer "B.CrtYd")
		)
		(fp_line
			(start -0.5 0.25)
			(end 0.498 0.25)
			(stroke
				(width 0.15)
				(type solid)
			)
			(layer "B.Fab")
		)
		(fp_line
			(start 0.498 0.25)
			(end 0.498 -0.248)
			(stroke
				(width 0.15)
				(type solid)
			)
			(layer "B.Fab")
		)
		(fp_line
			(start -0.5 -0.248)
			(end -0.5 0.25)
			(stroke
				(width 0.15)
				(type solid)
			)
			(layer "B.Fab")
		)
		(fp_line
			(start 0.498 -0.248)
			(end -0.5 -0.248)
			(stroke
				(width 0.15)
				(type solid)
			)
			(layer "B.Fab")
		)
		(pad "1" smd roundrect
			(at -0.5 0 180)
			(size 0.6 0.6)
			(layers "B.Cu" "B.Mask" "B.Paste")
			(roundrect_rratio 0.25)
			(net 1 "GND")
			(pintype "passive")
		)
		(pad "2" smd roundrect
			(at 0.498 0 270)
			(size 0.6 0.6)
			(layers "B.Cu" "B.Mask" "B.Paste")
			(roundrect_rratio 0.25)
			(net 206 "+1V1")
			(pintype "passive")
		)
	)
	(footprint "antmicro-footprints:C_0402_1005Metric"
		(layer "B.Cu")
		(at 102.1 159.55)
		(descr "Capacitor SMD 0402")
		(tags "capacitor SMD 0402")
		(property "Reference" "C160"
			(at 0 0.699 180)
			(layer "B.SilkS")
			(hide yes)
			(effects
				(font
					(size 0.7 0.7)
					(thickness 0.15)
				)
				(justify left bottom mirror)
			)
		)
		(property "Value" "C_100n_0402"
			(at -1.022927 -2.155213 180)
			(layer "B.Fab")
			(effects
				(font
					(size 0.7 0.7)
					(thickness 0.15)
				)
				(justify left bottom mirror)
			)
		)
		(property "Datasheet" "https://www.murata.com/products/productdetail?partno=GRM155R61H104KE14%23"
			(at 0 0 0)
			(layer "F.Fab")
			(hide yes)
			(effects
				(font
					(size 1.27 1.27)
					(thickness 0.15)
				)
			)
		)
		(property "Author" "Antmicro"
			(at 0 0 0)
			(layer "B.Fab")
			(hide yes)
			(effects
				(font
					(size 1 1)
					(thickness 0.15)
				)
				(justify mirror)
			)
		)
		(property "Dielectric" "X5R"
			(at 0 0 0)
			(layer "B.Fab")
			(hide yes)
			(effects
				(font
					(size 1 1)
					(thickness 0.15)
				)
				(justify mirror)
			)
		)
		(property "License" "Apache-2.0"
			(at 0 0 0)
			(layer "B.Fab")
			(hide yes)
			(effects
				(font
					(size 1 1)
					(thickness 0.15)
				)
				(justify mirror)
			)
		)
		(property "MPN" "GRM155R61H104KE14D"
			(at 0 0 0)
			(layer "B.Fab")
			(hide yes)
			(effects
				(font
					(size 1 1)
					(thickness 0.15)
				)
				(justify mirror)
			)
		)
		(property "Manufacturer" "Murata"
			(at 0 0 0)
			(layer "B.Fab")
			(hide yes)
			(effects
				(font
					(size 1 1)
					(thickness 0.15)
				)
				(justify mirror)
			)
		)
		(property "Val" "100n"
			(at 0 0 0)
			(layer "B.Fab")
			(hide yes)
			(effects
				(font
					(size 1 1)
					(thickness 0.15)
				)
				(justify mirror)
			)
		)
		(property "Voltage" "50V"
			(at 0 0 0)
			(layer "B.Fab")
			(hide yes)
			(effects
				(font
					(size 1 1)
					(thickness 0.15)
				)
				(justify mirror)
			)
		)
		(sheetname "/Ethernet/")
		(sheetfile "ethernet.kicad_sch")
		(attr smd)
		(fp_rect
			(start -0.9659 0.481258)
			(end 0.9649 -0.458742)
			(stroke
				(width 0.05)
				(type solid)
			)
			(fill no)
			(layer "B.CrtYd")
		)
		(fp_line
			(start -0.499 -0.248)
			(end -0.499 0.25)
			(stroke
				(width 0.15)
				(type solid)
			)
			(layer "B.Fab")
		)
		(fp_line
			(start -0.499 0.25)
			(end 0.499 0.25)
			(stroke
				(width 0.15)
				(type solid)
			)
			(layer "B.Fab")
		)
		(fp_line
			(start 0.499 -0.248)
			(end -0.499 -0.248)
			(stroke
				(width 0.15)
				(type solid)
			)
			(layer "B.Fab")
		)
		(fp_line
			(start 0.499 0.25)
			(end 0.499 -0.248)
			(stroke
				(width 0.15)
				(type solid)
			)
			(layer "B.Fab")
		)
		(pad "1" smd roundrect
			(at -0.484 0)
			(size 0.59 0.64)
			(layers "B.Cu" "B.Mask" "B.Paste")
			(roundrect_rratio 0.25)
			(net 1 "GND")
			(pintype "passive")
		)
		(pad "2" smd roundrect
			(at 0.484 0)
			(size 0.59 0.64)
			(layers "B.Cu" "B.Mask" "B.Paste")
			(roundrect_rratio 0.25)
			(net 200 "+3V3")
			(pintype "passive")
		)
	)
	(footprint "antmicro-footprints:R_0402_1005Metric"
		(layer "B.Cu")
		(at 159.700501 179.676)
		(descr "Resistor SMD 0402")
		(tags "resistor SMD 0402")
		(property "Reference" "R17"
			(at -1.122484 0.772697 180)
			(layer "B.SilkS")
			(hide yes)
			(effects
				(font
					(size 0.7 0.7)
					(thickness 0.15)
				)
				(justify left bottom mirror)
			)
		)
		(property "Value" "R_10k_0402"
			(at -1.011843 -1.772047 180)
			(layer "B.Fab")
			(effects
				(font
					(size 0.7 0.7)
					(thickness 0.15)
				)
				(justify left bottom mirror)
			)
		)
		(property "Datasheet" "https://www.bourns.com/docs/product-datasheets/cr.pdf"
			(at 0 0 0)
			(layer "F.Fab")
			(hide yes)
			(effects
				(font
					(size 1.27 1.27)
					(thickness 0.15)
				)
			)
		)
		(property "Author" "Antmicro"
			(at 0 0 0)
			(layer "B.Fab")
			(hide yes)
			(effects
				(font
					(size 1 1)
					(thickness 0.15)
				)
				(justify mirror)
			)
		)
		(property "License" "Apache-2.0"
			(at 0 0 0)
			(layer "B.Fab")
			(hide yes)
			(effects
				(font
					(size 1 1)
					(thickness 0.15)
				)
				(justify mirror)
			)
		)
		(property "MPN" "CR0402-FX-1002GLF"
			(at 0 0 0)
			(layer "B.Fab")
			(hide yes)
			(effects
				(font
					(size 1 1)
					(thickness 0.15)
				)
				(justify mirror)
			)
		)
		(property "Manufacturer" "Bourns"
			(at 0 0 0)
			(layer "B.Fab")
			(hide yes)
			(effects
				(font
					(size 1 1)
					(thickness 0.15)
				)
				(justify mirror)
			)
		)
		(property "Tolerance" "1%"
			(at 0 0 0)
			(layer "B.Fab")
			(hide yes)
			(effects
				(font
					(size 1 1)
					(thickness 0.15)
				)
				(justify mirror)
			)
		)
		(property "Val" "10k"
			(at 0 0 0)
			(layer "B.Fab")
			(hide yes)
			(effects
				(font
					(size 1 1)
					(thickness 0.15)
				)
				(justify mirror)
			)
		)
		(sheetname "/FPGA Config/")
		(sheetfile "fpga-config.kicad_sch")
		(attr smd)
		(fp_rect
			(start -0.93 0.47)
			(end 0.93 -0.47)
			(stroke
				(width 0.05)
				(type solid)
			)
			(fill no)
			(layer "B.CrtYd")
		)
		(fp_rect
			(start -0.5 0.25)
			(end 0.5 -0.25)
			(stroke
				(width 0.15)
				(type solid)
			)
			(fill no)
			(layer "B.Fab")
		)
		(pad "1" smd roundrect
			(at -0.485 0)
			(size 0.59 0.64)
			(layers "B.Cu" "B.Mask" "B.Paste")
			(roundrect_rratio 0.25)
			(net 633 "/FPGA Config/MODE0")
			(pintype "passive")
		)
		(pad "2" smd roundrect
			(at 0.485 0)
			(size 0.59 0.64)
			(layers "B.Cu" "B.Mask" "B.Paste")
			(roundrect_rratio 0.25)
			(net 200 "+3V3")
			(pintype "passive")
		)
	)
)
